# S9S_MB_2U (Grand Teton) — schematic netlist excerpt (pin names and nets, part order shuffled) for the footprints in the layout excerpt that follows; sources: Cadence DE-HDL packaged netlist, KiCad conversion of 03242023_DA0F0TMBIJ0_F0T_Motherboard_J_brd_V01_OCP.brd

J27  SCONN288_ADR50017P130CC  SCONN288_ADR50017-P130CC IO  pkg DDR288S_1-1VXB  page 108
  VIN_BULK0  = P12V_S3_AUX_CPU1_NVDIMM
  RFU0  = TP_CHF_CPU1_DIMM1_FRU_0
  VIN_MGMT  = P3V3_AUX
  HSCL  = I3C_SPD_DDREFGH_CPU1_LVC1_SCL_2
  HSDA  = I3C_SPD_DDREFGH_CPU1_LVC1_SDA
  VSS0  = GND
  DQ0_A  = M_F_CPU1_SA_DQ<0>
  VSS1  = GND
  DQ1_A  = M_F_CPU1_SA_DQ<1>
  VSS2  = GND
  DQS0_A_T  = M_F_CPU1_SA_DQS_DP<0>
  DQS0_A_C  = M_F_CPU1_SA_DQS_DN<0>
  VSS3  = GND
  DQ4_A  = M_F_CPU1_SA_DQ<4>
  VSS4  = GND
  DQ5_A  = M_F_CPU1_SA_DQ<5>
  VSS5  = GND
  DQ8_A  = M_F_CPU1_SA_DQ<8>
  VSS6  = GND
  DQ9_A  = M_F_CPU1_SA_DQ<9>
  VSS7  = GND
  DQS1_A_T  = M_F_CPU1_SA_DQS_DP<1>
  DQS1_A_C  = M_F_CPU1_SA_DQS_DN<1>
  VSS8  = GND
  DQ12_A  = M_F_CPU1_SA_DQ<12>
  VSS9  = GND
  DQ13_A  = M_F_CPU1_SA_DQ<13>
  VSS10  = GND
  DQ16_A  = M_F_CPU1_SA_DQ<16>
  VSS11  = GND
  DQ17_A  = M_F_CPU1_SA_DQ<17>
  VSS12  = GND
  DQS2_A_T  = M_F_CPU1_SA_DQS_DP<2>
  DQS2_A_C  = M_F_CPU1_SA_DQS_DN<2>
  VSS13  = GND
  DQ20_A  = M_F_CPU1_SA_DQ<20>
  VSS14  = GND
  DQ21_A  = M_F_CPU1_SA_DQ<21>
  VSS15  = GND
  DQ24_A  = M_F_CPU1_SA_DQ<24>
  VSS16  = GND
  DQ25_A  = M_F_CPU1_SA_DQ<25>
  VSS17  = GND
  DQS3_A_T  = M_F_CPU1_SA_DQS_DP<3>
  DQS3_A_C  = M_F_CPU1_SA_DQS_DN<3>
  VSS18  = GND
  DQ28_A  = M_F_CPU1_SA_DQ<28>
  VSS19  = GND
  DQ29_A  = M_F_CPU1_SA_DQ<29>
  VSS20  = GND
  CB0_A  = M_F_CPU1_SA_CB<0>
  VSS21  = GND
  CB1_A  = M_F_CPU1_SA_CB<1>
  VSS22  = GND
  DQS4_A_T  = M_F_CPU1_SA_DQS_DP<4>
  DQS4_A_C  = M_F_CPU1_SA_DQS_DN<4>
  VSS23  = GND
  CB4_A  = M_F_CPU1_SA_CB<4>
  VSS24  = GND
  CB5_A  = M_F_CPU1_SA_CB<5>
  VSS25  = GND
  ALERT_N  = M_F_CPU1_ALERT_N
  VSS26  = GND
  CS0_A_N  = M_F_CPU1_SA_CS_N<0>
  VSS27  = GND
  CA0_A  = M_F_CPU1_SA_CA<0>
  VSS28  = GND
  CA2_A  = M_F_CPU1_SA_CA<2>
  VSS29  = GND
  CA4_A  = M_F_CPU1_SA_CA<4>
  VSS30  = GND
  CA6_A  = M_F_CPU1_SA_CA<6>
  VSS31  = GND
  PAR_A  = M_F_CPU1_SA_PAR
  VSS32  = GND
  CA0_B  = M_F_CPU1_SB_CA<0>
  VSS33  = GND
  CA2_B  = M_F_CPU1_SB_CA<2>
  VSS34  = GND
  CA4_B  = M_F_CPU1_SB_CA<4>
  VSS35  = GND
  CA6_B  = M_F_CPU1_SB_CA<6>
  VSS36  = GND
  CS0_B_N  = M_F_CPU1_SB_CS_N<0>
  VSS37  = GND
  \lbd||rsp_a_n\  = M_F_CPU1_SA_RSP<0>
  \lbs||rsp_b_n\  = M_F_CPU1_SB_RSP<0>
  VSS38  = GND
  CB4_B  = M_F_CPU1_SB_CB<4>
  VSS39  = GND
  CB5_B  = M_F_CPU1_SB_CB<5>
  VSS40  = GND
  \dqs9_b_t||tdqs9_b_t||dbi4_b_n\  = M_F_CPU1_SB_DQS_DP<9>
  \dqs9_b_c||tdqs9_b_c\  = M_F_CPU1_SB_DQS_DN<9>
  VSS41  = GND
  CB0_B  = M_F_CPU1_SB_CB<0>
  VSS42  = GND
  CB1_B  = M_F_CPU1_SB_CB<1>
  VSS43  = GND
  DQ0_B  = M_F_CPU1_SB_DQ<0>
  VSS44  = GND
  DQ1_B  = M_F_CPU1_SB_DQ<1>
  VSS45  = GND
  DQS0_B_T  = M_F_CPU1_SB_DQS_DP<0>
  DQS0_B_C  = M_F_CPU1_SB_DQS_DN<0>
  VSS46  = GND
  DQ4_B  = M_F_CPU1_SB_DQ<4>
  VSS47  = GND
  DQ5_B  = M_F_CPU1_SB_DQ<5>
  VSS48  = GND
  DQ8_B  = M_F_CPU1_SB_DQ<8>
  VSS49  = GND
  DQ9_B  = M_F_CPU1_SB_DQ<9>
  VSS50  = GND
  DQS1_B_T  = M_F_CPU1_SB_DQS_DP<1>
  DQS1_B_C  = M_F_CPU1_SB_DQS_DN<1>
  VSS51  = GND
  DQ12_B  = M_F_CPU1_SB_DQ<12>
  VSS52  = GND
  DQ13_B  = M_F_CPU1_SB_DQ<13>
  VSS53  = GND
  DQ16_B  = M_F_CPU1_SB_DQ<16>
  VSS54  = GND
  DQ17_B  = M_F_CPU1_SB_DQ<17>
  VSS55  = GND
  DQS2_B_T  = M_F_CPU1_SB_DQS_DP<2>
  DQS2_B_C  = M_F_CPU1_SB_DQS_DN<2>
  VSS56  = GND
  DQ20_B  = M_F_CPU1_SB_DQ<20>
  VSS57  = GND
  DQ21_B  = M_F_CPU1_SB_DQ<21>
  VSS58  = GND
  DQ24_B  = M_F_CPU1_SB_DQ<24>
  VSS59  = GND
  DQ25_B  = M_F_CPU1_SB_DQ<25>
  VSS60  = GND
  DQS3_B_T  = M_F_CPU1_SB_DQS_DP<3>
  DQS3_B_C  = M_F_CPU1_SB_DQS_DN<3>
  VSS61  = GND
  DQ28_B  = M_F_CPU1_SB_DQ<28>
  VSS62  = GND
  DQ29_B  = M_F_CPU1_SB_DQ<29>
  VSS63  = GND
  RFU1  = TP_CHF_CPU1_DIMM1_FRU_1
  VIN_BULK1  = P12V_S3_AUX_CPU1_NVDIMM
  VIN_BULK2  = P12V_S3_AUX_CPU1_NVDIMM
  \pwr_good||fail_n\  = PWRGD_CHF_CPU1_DIMM1
  HSA  = PD_CHF_CPU1_DIMM1_SAA
  RFU2  = TP_CHF_CPU1_DIMM1_FRU_2
  RFU3  = TP_CHF_CPU1_DIMM1_FRU_3
  VSS64  = GND
  DQ2_A  = M_F_CPU1_SA_DQ<2>
  VSS65  = GND
  DQ3_A  = M_F_CPU1_SA_DQ<3>
  VSS66  = GND
  \dqs5_a_c||tdqs5_a_c||dqs5_a_t||tdqs5_a_t\  = M_F_CPU1_SA_DQS_DN<5>
  \dqs5_a_t||tdqs5_a_t\  = M_F_CPU1_SA_DQS_DP<5>
  VSS67  = GND
  DQ6_A  = M_F_CPU1_SA_DQ<6>
  VSS68  = GND
  DQ7_A  = M_F_CPU1_SA_DQ<7>
  VSS69  = GND
  DQ10_A  = M_F_CPU1_SA_DQ<10>
  VSS70  = GND
  DQ11_A  = M_F_CPU1_SA_DQ<11>
  VSS71  = GND
  \dqs6_a_c||tdqs6_a_c||dqs6_a_t||tdqs6_a_t\  = M_F_CPU1_SA_DQS_DN<6>
  \dqs6_a_t||tdqs6_a_t\  = M_F_CPU1_SA_DQS_DP<6>
  VSS72  = GND
  DQ14_A  = M_F_CPU1_SA_DQ<14>
  VSS73  = GND
  DQ15_A  = M_F_CPU1_SA_DQ<15>
  VSS74  = GND
  DQ18_A  = M_F_CPU1_SA_DQ<18>
  VSS75  = GND
  DQ19_A  = M_F_CPU1_SA_DQ<19>
  VSS76  = GND
  \dqs7_a_c||tdqs7_a_c\  = M_F_CPU1_SA_DQS_DN<7>
  \dqs7_a_t||tdqs7_a_t\  = M_F_CPU1_SA_DQS_DP<7>
  VSS77  = GND
  DQ22_A  = M_F_CPU1_SA_DQ<22>
  VSS78  = GND
  DQ23_A  = M_F_CPU1_SA_DQ<23>
  VSS79  = GND
  DQ26_A  = M_F_CPU1_SA_DQ<26>
  VSS80  = GND
  DQ27_A  = M_F_CPU1_SA_DQ<27>
  VSS81  = GND
  \dqs8_a_c||tdqs8_a_c\  = M_F_CPU1_SA_DQS_DN<8>
  \dqs8_a_t||tdqs8_a_t\  = M_F_CPU1_SA_DQS_DP<8>
  VSS82  = GND
  DQ30_A  = M_F_CPU1_SA_DQ<30>
  VSS83  = GND
  DQ31_A  = M_F_CPU1_SA_DQ<31>
  VSS84  = GND
  CB2_A  = M_F_CPU1_SA_CB<2>
  VSS85  = GND
  CB3_A  = M_F_CPU1_SA_CB<3>
  VSS86  = GND
  \dqs9_a_c||tdqs9_a_c\  = M_F_CPU1_SA_DQS_DN<9>
  \dqs9_a_t||tdqs9_a_t\  = M_F_CPU1_SA_DQS_DP<9>
  VSS87  = GND
  CB6_A  = M_F_CPU1_SA_CB<6>
  VSS88  = GND
  CB7_A  = M_F_CPU1_SA_CB<7>
  VSS89  = GND
  RESET_N  = RST_M_EF_CPU1_FPGA_N
  VSS90  = GND
  CS1_A_N  = M_F_CPU1_SA_CS_N<1>
  VSS91  = GND
  CA1_A  = M_F_CPU1_SA_CA<1>
  VSS92  = GND
  CA3_A  = M_F_CPU1_SA_CA<3>
  VSS93  = GND
  CA5_A  = M_F_CPU1_SA_CA<5>
  VSS94  = GND
  CK_T  = M_F_CPU1_CLK_DP<0>
  CK_C  = M_F_CPU1_CLK_DN<0>
  VSS95  = GND
  RFU4  = TP_CHF_CPU1_DIMM1_FRU_4
  CA1_B  = M_F_CPU1_SB_CA<1>
  VSS96  = GND
  CA3_B  = M_F_CPU1_SB_CA<3>
  VSS97  = GND
  CA5_B  = M_F_CPU1_SB_CA<5>
  VSS98  = GND
  PAR_B  = M_F_CPU1_SB_PAR
  VSS99  = GND
  CS1_B_N  = M_F_CPU1_SB_CS_N<1>
  VSS100  = GND
  RFU5  = TP_CHF_CPU1_DIMM1_FRU_5
  RFU6  = TP_CHF_CPU1_DIMM1_FRU_6
  VSS101  = GND
  CB6_B  = M_F_CPU1_SB_CB<6>
  VSS102  = GND
  CB7_B  = M_F_CPU1_SB_CB<7>
  VSS103  = GND
  DQS4_B_C  = M_F_CPU1_SB_DQS_DN<4>
  DQS4_B_T  = M_F_CPU1_SB_DQS_DP<4>
  VSS104  = GND
  CB2_B  = M_F_CPU1_SB_CB<2>
  VSS105  = GND
  CB3_B  = M_F_CPU1_SB_CB<3>
  VSS106  = GND
  DQ2_B  = M_F_CPU1_SB_DQ<2>
  VSS107  = GND
  DQ3_B  = M_F_CPU1_SB_DQ<3>
  VSS108  = GND
  \dqs5_b_c||tdqs5_b_c\  = M_F_CPU1_SB_DQS_DN<5>
  \dqs5_b_t||tdqs5_b_t\  = M_F_CPU1_SB_DQS_DP<5>
  VSS109  = GND
  DQ6_B  = M_F_CPU1_SB_DQ<6>
  VSS110  = GND
  DQ7_B  = M_F_CPU1_SB_DQ<7>
  VSS111  = GND
  DQ10_B  = M_F_CPU1_SB_DQ<10>
  VSS112  = GND
  DQ11_B  = M_F_CPU1_SB_DQ<11>
  VSS113  = GND
  \dqs6_b_c||tdqs6_b_c\  = M_F_CPU1_SB_DQS_DN<6>
  \dqs6_b_t||tdqs6_b_t\  = M_F_CPU1_SB_DQS_DP<6>
  VSS114  = GND
  DQ14_B  = M_F_CPU1_SB_DQ<14>
  VSS115  = GND
  DQ15_B  = M_F_CPU1_SB_DQ<15>
  VSS116  = GND
  DQ18_B  = M_F_CPU1_SB_DQ<18>
  VSS117  = GND
  DQ19_B  = M_F_CPU1_SB_DQ<19>
  VSS118  = GND
  \dqs7_b_c||tdqs7_b_c\  = M_F_CPU1_SB_DQS_DN<7>
  \dqs7_b_t||tdqs7_b_t\  = M_F_CPU1_SB_DQS_DP<7>
  VSS119  = GND
  DQ22_B  = M_F_CPU1_SB_DQ<22>
  VSS120  = GND
  DQ23_B  = M_F_CPU1_SB_DQ<23>
  VSS121  = GND
  DQ26_B  = M_F_CPU1_SB_DQ<26>
  VSS122  = GND
  DQ27_B  = M_F_CPU1_SB_DQ<27>
  VSS123  = GND
  \dqs8_b_c||tdqs8_b_c\  = M_F_CPU1_SB_DQS_DN<8>
  \dqs8_b_t||tdqs8_b_t\  = M_F_CPU1_SB_DQS_DP<8>
  VSS124  = GND
  DQ30_B  = M_F_CPU1_SB_DQ<30>
  VSS125  = GND
  DQ31_B  = M_F_CPU1_SB_DQ<31>
  VSS126  = GND
  G1  = GND
  G2  = GND
  G3  = GND

(kicad_pcb
	(version 20260206)
	(generator "pcbnew")
	(generator_version "10.0")
	(general
		(thickness 1.6)
		(legacy_teardrops no)
	)
	(paper "A4")
	(title_block
		(title "03242023_DA0F0TMBIJ0_F0T_Motherboard_J_brd_V01_OCP.brd")
		(comment 1 "Grand Teton / footprint 1301 of 6105 (J27), pads 92-137 of 291")
	)
	(layers
		(0 "F.Cu" signal "TOP")
		(4 "In1.Cu" signal "GND")
		(6 "In2.Cu" signal "IN1")
		(8 "In3.Cu" signal "GND1")
		(10 "In4.Cu" signal "IN2")
		(12 "In5.Cu" signal "GND2")
		(14 "In6.Cu" signal "IN3")
		(16 "In7.Cu" signal "GND3")
		(18 "In8.Cu" signal "VCC")
		(20 "In9.Cu" signal "VCC1")
		(22 "In10.Cu" signal "GND4")
		(24 "In11.Cu" signal "IN4")
		(26 "In12.Cu" signal "GND5")
		(28 "In13.Cu" signal "IN5")
		(30 "In14.Cu" signal "GND6")
		(32 "In15.Cu" signal "IN6")
		(34 "In16.Cu" signal "GND7")
		(2 "B.Cu" signal "BOTTOM")
		(9 "F.Adhes" user "F.Adhesive")
		(11 "B.Adhes" user "B.Adhesive")
		(13 "F.Paste" user "Package Geometry/Pastemask Top")
		(15 "B.Paste" user "Package Geometry/Pastemask Bottom")
		(5 "F.SilkS" user "Ref Des/Silkscreen Top")
		(7 "B.SilkS" user "Ref Des/Silkscreen Bottom")
		(1 "F.Mask" user "Board Geometry/Soldermask Top")
		(3 "B.Mask" user "Board Geometry/Soldermask Bottom")
		(17 "Dwgs.User" user "User.Drawings")
		(19 "Cmts.User" user "User.Comments")
		(21 "Eco1.User" user "User.Eco1")
		(23 "Eco2.User" user "User.Eco2")
		(25 "Edge.Cuts" user "Board Geometry/Outline")
		(27 "Margin" user)
		(31 "F.CrtYd" user "Package Geometry/Place Bound Top")
		(29 "B.CrtYd" user "Package Geometry/Place Bound Bottom")
		(35 "F.Fab" user "Ref Des/Assembly Top")
		(33 "B.Fab" user "Ref Des/Assembly Bottom")
	)
	(footprint ""
		(layer "F.Cu")
		(at 183.49468 -258.091686)
		(property "Reference" "J27"
			(at 2.19456 -81.755488 0)
			(unlocked yes)
			(layer "F.SilkS")
			(effects
				(font
					(size 0.7874 0.5842)
					(thickness 0.1524)
				)
				(justify left)
			)
		)
		(property "Value" ""
			(at 0 0 0)
			(layer "F.Fab")
			(effects
				(font
					(size 1.27 1.27)
				)
			)
		)
		(duplicate_pad_numbers_are_jumpers no)
		(pad "92" smd rect
			(at -2.050034 19.12493 270)
			(size 0.519938 1.4986)
			(layers "F.Cu" "F.Mask" "F.Paste")
			(net "GND")
		)
		(pad "93" smd rect
			(at -2.050034 19.975068 270)
			(size 0.519938 1.4986)
			(layers "F.Cu" "F.Mask" "F.Paste")
			(net "M_F_CPU1_SB_DQS_DP<9>")
		)
		(pad "94" smd rect
			(at -2.050034 20.824952 270)
			(size 0.519938 1.4986)
			(layers "F.Cu" "F.Mask" "F.Paste")
			(net "M_F_CPU1_SB_DQS_DN<9>")
		)
		(pad "95" smd rect
			(at -2.050034 21.67509 270)
			(size 0.519938 1.4986)
			(layers "F.Cu" "F.Mask" "F.Paste")
			(net "GND")
		)
		(pad "96" smd rect
			(at -2.050034 22.524974 270)
			(size 0.519938 1.4986)
			(layers "F.Cu" "F.Mask" "F.Paste")
			(net "M_F_CPU1_SB_CB<0>")
		)
		(pad "97" smd rect
			(at -2.050034 23.375112 270)
			(size 0.519938 1.4986)
			(layers "F.Cu" "F.Mask" "F.Paste")
			(net "GND")
		)
		(pad "98" smd rect
			(at -2.050034 24.224996 270)
			(size 0.519938 1.4986)
			(layers "F.Cu" "F.Mask" "F.Paste")
			(net "M_F_CPU1_SB_CB<1>")
		)
		(pad "99" smd rect
			(at -2.050034 25.07488 270)
			(size 0.519938 1.4986)
			(layers "F.Cu" "F.Mask" "F.Paste")
			(net "GND")
		)
		(pad "100" smd rect
			(at -2.050034 25.925018 270)
			(size 0.519938 1.4986)
			(layers "F.Cu" "F.Mask" "F.Paste")
			(net "M_F_CPU1_SB_DQ<0>")
		)
		(pad "101" smd rect
			(at -2.050034 26.774902 270)
			(size 0.519938 1.4986)
			(layers "F.Cu" "F.Mask" "F.Paste")
			(net "GND")
		)
		(pad "102" smd rect
			(at -2.050034 27.62504 270)
			(size 0.519938 1.4986)
			(layers "F.Cu" "F.Mask" "F.Paste")
			(net "M_F_CPU1_SB_DQ<1>")
		)
		(pad "103" smd rect
			(at -2.050034 28.474924 270)
			(size 0.519938 1.4986)
			(layers "F.Cu" "F.Mask" "F.Paste")
			(net "GND")
		)
		(pad "104" smd rect
			(at -2.050034 29.325062 270)
			(size 0.519938 1.4986)
			(layers "F.Cu" "F.Mask" "F.Paste")
			(net "M_F_CPU1_SB_DQS_DP<0>")
		)
		(pad "105" smd rect
			(at -2.050034 30.174946 270)
			(size 0.519938 1.4986)
			(layers "F.Cu" "F.Mask" "F.Paste")
			(net "M_F_CPU1_SB_DQS_DN<0>")
		)
		(pad "106" smd rect
			(at -2.050034 31.025084 270)
			(size 0.519938 1.4986)
			(layers "F.Cu" "F.Mask" "F.Paste")
			(net "GND")
		)
		(pad "107" smd rect
			(at -2.050034 31.874968 270)
			(size 0.519938 1.4986)
			(layers "F.Cu" "F.Mask" "F.Paste")
			(net "M_F_CPU1_SB_DQ<4>")
		)
		(pad "108" smd rect
			(at -2.050034 32.725106 270)
			(size 0.519938 1.4986)
			(layers "F.Cu" "F.Mask" "F.Paste")
			(net "GND")
		)
		(pad "109" smd rect
			(at -2.050034 33.57499 270)
			(size 0.519938 1.4986)
			(layers "F.Cu" "F.Mask" "F.Paste")
			(net "M_F_CPU1_SB_DQ<5>")
		)
		(pad "110" smd rect
			(at -2.050034 34.425128 270)
			(size 0.519938 1.4986)
			(layers "F.Cu" "F.Mask" "F.Paste")
			(net "GND")
		)
		(pad "111" smd rect
			(at -2.050034 35.275012 270)
			(size 0.519938 1.4986)
			(layers "F.Cu" "F.Mask" "F.Paste")
			(net "M_F_CPU1_SB_DQ<8>")
		)
		(pad "112" smd rect
			(at -2.050034 36.124896 270)
			(size 0.519938 1.4986)
			(layers "F.Cu" "F.Mask" "F.Paste")
			(net "GND")
		)
		(pad "113" smd rect
			(at -2.050034 36.975034 270)
			(size 0.519938 1.4986)
			(layers "F.Cu" "F.Mask" "F.Paste")
			(net "M_F_CPU1_SB_DQ<9>")
		)
		(pad "114" smd rect
			(at -2.050034 37.824918 270)
			(size 0.519938 1.4986)
			(layers "F.Cu" "F.Mask" "F.Paste")
			(net "GND")
		)
		(pad "115" smd rect
			(at -2.050034 38.675056 270)
			(size 0.519938 1.4986)
			(layers "F.Cu" "F.Mask" "F.Paste")
			(net "M_F_CPU1_SB_DQS_DP<1>")
		)
		(pad "116" smd rect
			(at -2.050034 39.52494 270)
			(size 0.519938 1.4986)
			(layers "F.Cu" "F.Mask" "F.Paste")
			(net "M_F_CPU1_SB_DQS_DN<1>")
		)
		(pad "117" smd rect
			(at -2.050034 40.375078 270)
			(size 0.519938 1.4986)
			(layers "F.Cu" "F.Mask" "F.Paste")
			(net "GND")
		)
		(pad "118" smd rect
			(at -2.050034 41.224962 270)
			(size 0.519938 1.4986)
			(layers "F.Cu" "F.Mask" "F.Paste")
			(net "M_F_CPU1_SB_DQ<12>")
		)
		(pad "119" smd rect
			(at -2.050034 42.0751 270)
			(size 0.519938 1.4986)
			(layers "F.Cu" "F.Mask" "F.Paste")
			(net "GND")
		)
		(pad "120" smd rect
			(at -2.050034 42.924984 270)
			(size 0.519938 1.4986)
			(layers "F.Cu" "F.Mask" "F.Paste")
			(net "M_F_CPU1_SB_DQ<13>")
		)
		(pad "121" smd rect
			(at -2.050034 43.775122 270)
			(size 0.519938 1.4986)
			(layers "F.Cu" "F.Mask" "F.Paste")
			(net "GND")
		)
		(pad "122" smd rect
			(at -2.050034 44.625006 270)
			(size 0.519938 1.4986)
			(layers "F.Cu" "F.Mask" "F.Paste")
			(net "M_F_CPU1_SB_DQ<16>")
		)
		(pad "123" smd rect
			(at -2.050034 45.47489 270)
			(size 0.519938 1.4986)
			(layers "F.Cu" "F.Mask" "F.Paste")
			(net "GND")
		)
		(pad "124" smd rect
			(at -2.050034 46.325028 270)
			(size 0.519938 1.4986)
			(layers "F.Cu" "F.Mask" "F.Paste")
			(net "M_F_CPU1_SB_DQ<17>")
		)
		(pad "125" smd rect
			(at -2.050034 47.174912 270)
			(size 0.519938 1.4986)
			(layers "F.Cu" "F.Mask" "F.Paste")
			(net "GND")
		)
		(pad "126" smd rect
			(at -2.050034 48.02505 270)
			(size 0.519938 1.4986)
			(layers "F.Cu" "F.Mask" "F.Paste")
			(net "M_F_CPU1_SB_DQS_DP<2>")
		)
		(pad "127" smd rect
			(at -2.050034 48.874934 270)
			(size 0.519938 1.4986)
			(layers "F.Cu" "F.Mask" "F.Paste")
			(net "M_F_CPU1_SB_DQS_DN<2>")
		)
		(pad "128" smd rect
			(at -2.050034 49.725072 270)
			(size 0.519938 1.4986)
			(layers "F.Cu" "F.Mask" "F.Paste")
			(net "GND")
		)
		(pad "129" smd rect
			(at -2.050034 50.574956 270)
			(size 0.519938 1.4986)
			(layers "F.Cu" "F.Mask" "F.Paste")
			(net "M_F_CPU1_SB_DQ<20>")
		)
		(pad "130" smd rect
			(at -2.050034 51.425094 270)
			(size 0.519938 1.4986)
			(layers "F.Cu" "F.Mask" "F.Paste")
			(net "GND")
		)
		(pad "131" smd rect
			(at -2.050034 52.274978 270)
			(size 0.519938 1.4986)
			(layers "F.Cu" "F.Mask" "F.Paste")
			(net "M_F_CPU1_SB_DQ<21>")
		)
		(pad "132" smd rect
			(at -2.050034 53.125116 270)
			(size 0.519938 1.4986)
			(layers "F.Cu" "F.Mask" "F.Paste")
			(net "GND")
		)
		(pad "133" smd rect
			(at -2.050034 53.975 270)
			(size 0.519938 1.4986)
			(layers "F.Cu" "F.Mask" "F.Paste")
			(net "M_F_CPU1_SB_DQ<24>")
		)
		(pad "134" smd rect
			(at -2.050034 54.824884 270)
			(size 0.519938 1.4986)
			(layers "F.Cu" "F.Mask" "F.Paste")
			(net "GND")
		)
		(pad "135" smd rect
			(at -2.050034 55.675022 270)
			(size 0.519938 1.4986)
			(layers "F.Cu" "F.Mask" "F.Paste")
			(net "M_F_CPU1_SB_DQ<25>")
		)
		(pad "136" smd rect
			(at -2.050034 56.524906 270)
			(size 0.519938 1.4986)
			(layers "F.Cu" "F.Mask" "F.Paste")
			(net "GND")
		)
		(pad "137" smd rect
			(at -2.050034 57.375044 270)
			(size 0.519938 1.4986)
			(layers "F.Cu" "F.Mask" "F.Paste")
			(net "M_F_CPU1_SB_DQS_DP<3>")
		)
	)
)
